(kicad_pcb
	(version 20260206)
	(generator "pcbnew")
	(generator_version "10.0")
	(general
		(thickness 1.6)
		(legacy_teardrops no)
	)
	(paper "A4")
	(title_block
		(title "v1-chassis-manager — T6M_CM_d_v01_1031_1645.brd")
		(comment 1 "Open CloudServer (Microsoft) / footprints 1050-1053 of 2512")
	)
	(layers
		(0 "F.Cu" signal "TOP")
		(4 "In1.Cu" signal "GND1")
		(6 "In2.Cu" signal "IN1")
		(8 "In3.Cu" signal "VCC1")
		(10 "In4.Cu" signal "VCC2")
		(12 "In5.Cu" signal "GND2")
		(14 "In6.Cu" signal "IN2")
		(16 "In7.Cu" signal "IN3")
		(18 "In8.Cu" signal "GND3")
		(2 "B.Cu" signal "BOTTOM")
		(9 "F.Adhes" user "F.Adhesive")
		(11 "B.Adhes" user "B.Adhesive")
		(13 "F.Paste" user "Package Geometry/Pastemask Top")
		(15 "B.Paste" user "Package Geometry/Pastemask Bottom")
		(5 "F.SilkS" user "Ref Des/Silkscreen Top")
		(7 "B.SilkS" user "Ref Des/Silkscreen Bottom")
		(1 "F.Mask" user "Board Geometry/Soldermask Top")
		(3 "B.Mask" user "Board Geometry/Soldermask Bottom")
		(17 "Dwgs.User" user "User.Drawings")
		(19 "Cmts.User" user "User.Comments")
		(21 "Eco1.User" user "User.Eco1")
		(23 "Eco2.User" user "User.Eco2")
		(25 "Edge.Cuts" user "Board Geometry/Outline")
		(27 "Margin" user)
		(31 "F.CrtYd" user "Package Geometry/Place Bound Top")
		(29 "B.CrtYd" user "Package Geometry/Place Bound Bottom")
		(35 "F.Fab" user "Ref Des/Assembly Top")
		(33 "B.Fab" user "Ref Des/Assembly Bottom")
	)
	(footprint ""
		(layer "F.Cu")
		(at 36.203128 -11.393678)
		(property "Reference" "PU7"
			(at -7.701788 1.185164 0)
			(unlocked yes)
			(layer "F.SilkS")
			(effects
				(font
					(size 0.7874 0.5842)
					(thickness 0.1524)
				)
			)
		)
		(property "Value" ""
			(at 0 0 0)
			(layer "F.Fab")
			(effects
				(font
					(size 1.27 1.27)
				)
			)
		)
		(duplicate_pad_numbers_are_jumpers no)
		(fp_line
			(start 0.3302 -0.0762)
			(end 0.7112 -0.4572)
			(stroke
				(width 0.1524)
				(type default)
			)
			(layer "F.SilkS")
		)
		(fp_line
			(start 0.3302 0.0254)
			(end 0.3302 -0.0762)
			(stroke
				(width 0.1524)
				(type default)
			)
			(layer "F.SilkS")
		)
		(fp_line
			(start 0.3302 2.159)
			(end 0.3302 2.6416)
			(stroke
				(width 0.1524)
				(type default)
			)
			(layer "F.SilkS")
		)
		(fp_line
			(start 0.3302 2.6416)
			(end 0.8128 2.6416)
			(stroke
				(width 0.1524)
				(type default)
			)
			(layer "F.SilkS")
		)
		(fp_line
			(start 0.7112 -0.4572)
			(end 0.8128 -0.4572)
			(stroke
				(width 0.1524)
				(type default)
			)
			(layer "F.SilkS")
		)
		(fp_line
			(start 2.9718 -0.4572)
			(end 3.429 -0.4572)
			(stroke
				(width 0.1524)
				(type default)
			)
			(layer "F.SilkS")
		)
		(fp_line
			(start 3.429 -0.4572)
			(end 3.429 0.0254)
			(stroke
				(width 0.1524)
				(type default)
			)
			(layer "F.SilkS")
		)
		(fp_line
			(start 3.429 2.1844)
			(end 3.429 2.6416)
			(stroke
				(width 0.1524)
				(type default)
			)
			(layer "F.SilkS")
		)
		(fp_line
			(start 3.429 2.6416)
			(end 2.9464 2.6416)
			(stroke
				(width 0.1524)
				(type default)
			)
			(layer "F.SilkS")
		)
		(fp_poly
			(pts
				(xy -0.85852 0.480568) (xy -0.85852 -0.144272) (xy -0.3048 0.183896)
			)
			(stroke
				(width 0)
				(type default)
			)
			(fill yes)
			(layer "F.SilkS")
		)
		(fp_poly
			(pts
				(xy 3.429508 2.642108) (xy 3.429508 2.0828) (xy 3.429508 2.032) (xy 3.937 2.032) (xy 3.937 0.1524)
				(xy 3.429508 0.1524) (xy 3.429508 0.127) (xy 3.429508 0.1016) (xy 3.429508 -0.457708) (xy 2.8702 -0.457708)
				(xy 2.8194 -0.457708) (xy 2.8194 -0.9652) (xy 0.9398 -0.9652) (xy 0.9398 -0.457708) (xy 0.889 -0.457708)
				(xy 0.329692 -0.457708) (xy 0.329692 0.1016) (xy 0.3302 0.1016) (xy 0.3302 0.1524) (xy -0.1778 0.1524)
				(xy -0.1778 2.032) (xy 0.329692 2.032) (xy 0.329692 2.0828) (xy 0.329692 2.642108) (xy 0.889 2.642108)
				(xy 0.9398 2.642108) (xy 0.9398 3.1496) (xy 2.8194 3.1496) (xy 2.8194 2.6416) (xy 3.0226 2.6416)
				(xy 3.0226 2.642108)
			)
			(stroke
				(width 0)
				(type default)
			)
			(fill no)
			(layer "F.CrtYd")
		)
		(fp_line
			(start 0.329692 -0.457708)
			(end 3.429508 -0.457708)
			(stroke
				(width 0.1)
				(type default)
			)
			(layer "F.Fab")
		)
		(fp_line
			(start 0.329692 2.642108)
			(end 0.329692 -0.457708)
			(stroke
				(width 0.1)
				(type default)
			)
			(layer "F.Fab")
		)
		(fp_line
			(start 3.429508 -0.457708)
			(end 3.429508 2.642108)
			(stroke
				(width 0.1)
				(type default)
			)
			(layer "F.Fab")
		)
		(fp_line
			(start 3.429508 2.642108)
			(end 0.329692 2.642108)
			(stroke
				(width 0.1)
				(type default)
			)
			(layer "F.Fab")
		)
		(fp_poly
			(pts
				(xy -0.96266 0.54102) (xy -0.96266 -0.08382) (xy -0.40894 0.244348)
			)
			(stroke
				(width 0)
				(type default)
			)
			(fill yes)
			(layer "F.Fab")
		)
		(fp_text user "1"
			(at -0.656082 -0.602488 0)
			(unlocked yes)
			(layer "F.SilkS")
			(effects
				(font
					(size 0.635 0.4064)
					(thickness 0.1524)
				)
			)
		)
		(fp_text user "5"
			(at -0.567944 1.704594 0)
			(unlocked yes)
			(layer "F.SilkS")
			(effects
				(font
					(size 0.635 0.4064)
					(thickness 0.1524)
				)
			)
		)
		(fp_text user "20"
			(at 0.205486 -1.008634 0)
			(unlocked yes)
			(layer "F.SilkS")
			(effects
				(font
					(size 0.635 0.4064)
					(thickness 0.1524)
				)
			)
		)
		(fp_text user "6"
			(at 0.713486 3.44043 0)
			(unlocked yes)
			(layer "F.SilkS")
			(effects
				(font
					(size 0.635 0.4064)
					(thickness 0.1524)
				)
			)
		)
		(fp_text user "16"
			(at 3.052572 -1.465834 0)
			(unlocked yes)
			(layer "F.SilkS")
			(effects
				(font
					(size 0.635 0.4064)
					(thickness 0.1524)
				)
			)
		)
		(fp_text user "10"
			(at 3.209798 3.577336 0)
			(unlocked yes)
			(layer "F.SilkS")
			(effects
				(font
					(size 0.635 0.4064)
					(thickness 0.1524)
				)
			)
		)
		(fp_text user "11"
			(at 4.30403 2.916428 0)
			(unlocked yes)
			(layer "F.SilkS")
			(effects
				(font
					(size 0.635 0.4064)
					(thickness 0.1524)
				)
			)
		)
		(fp_text user "15"
			(at 4.442714 -0.169164 0)
			(unlocked yes)
			(layer "F.SilkS")
			(effects
				(font
					(size 0.635 0.4064)
					(thickness 0.1524)
				)
			)
		)
		(fp_text user "1"
			(at -0.332232 0.064516 0)
			(unlocked yes)
			(layer "F.Fab")
			(effects
				(font
					(size 0.7874 0.5842)
					(thickness 0.000001)
				)
			)
		)
		(fp_text user "5"
			(at -0.230632 2.655316 0)
			(unlocked yes)
			(layer "F.Fab")
			(effects
				(font
					(size 0.7874 0.5842)
					(thickness 0.000001)
				)
			)
		)
		(fp_text user "20"
			(at 0.2032 -0.91313 0)
			(unlocked yes)
			(layer "F.Fab")
			(effects
				(font
					(size 0.7874 0.5842)
					(thickness 0.000001)
				)
			)
		)
		(fp_text user "6"
			(at 0.963168 3.645916 0)
			(unlocked yes)
			(layer "F.Fab")
			(effects
				(font
					(size 0.7874 0.5842)
					(thickness 0.000001)
				)
			)
		)
		(fp_text user "10"
			(at 2.944622 3.595116 0)
			(unlocked yes)
			(layer "F.Fab")
			(effects
				(font
					(size 0.7874 0.5842)
					(thickness 0.000001)
				)
			)
		)
		(fp_text user "16"
			(at 3.429 -0.98933 0)
			(unlocked yes)
			(layer "F.Fab")
			(effects
				(font
					(size 0.7874 0.5842)
					(thickness 0.000001)
				)
			)
		)
		(fp_text user "11"
			(at 4.6228 2.69367 0)
			(unlocked yes)
			(layer "F.Fab")
			(effects
				(font
					(size 0.7874 0.5842)
					(thickness 0.000001)
				)
			)
		)
		(fp_text user "15"
			(at 4.646422 0.115316 0)
			(unlocked yes)
			(layer "F.Fab")
			(effects
				(font
					(size 0.7874 0.5842)
					(thickness 0.000001)
				)
			)
		)
		(pad "1" smd rect
			(at 0.316738 0.2921 270)
			(size 0.1778 0.9144)
			(layers "F.Cu" "F.Mask" "F.Paste")
			(net "VSENSE_PV_VDDR_NODE1_N")
		)
		(pad "2" smd rect
			(at 0.316738 0.69215 270)
			(size 0.1778 0.9144)
			(layers "F.Cu" "F.Mask" "F.Paste")
			(net "PV_VDDR_NODE1_V1")
		)
		(pad "3" smd rect
			(at 0.316738 1.0922 270)
			(size 0.1778 0.9144)
			(layers "F.Cu" "F.Mask" "F.Paste")
			(net "PV_VDDR_NODE1_V1")
		)
		(pad "4" smd rect
			(at 0.316738 1.49225 270)
			(size 0.1778 0.9144)
			(layers "F.Cu" "F.Mask" "F.Paste")
			(net "PV_VDDR_NODE1_V1")
		)
		(pad "5" smd rect
			(at 0.316738 1.8923 270)
			(size 0.1778 0.9144)
			(layers "F.Cu" "F.Mask" "F.Paste")
			(net "PV_VDDR_NODE1_V0")
		)
		(pad "6" smd rect
			(at 1.0795 2.655062)
			(size 0.1778 0.9144)
			(layers "F.Cu" "F.Mask" "F.Paste")
			(net "PV_VDDR_NODE1_VREF")
		)
		(pad "7" smd rect
			(at 1.47955 2.655062)
			(size 0.1778 0.9144)
			(layers "F.Cu" "F.Mask" "F.Paste")
			(net "PWRGD_NODE1_PVDDR_STB_PG")
		)
		(pad "8" smd rect
			(at 1.8796 2.655062)
			(size 0.1778 0.9144)
			(layers "F.Cu" "F.Mask" "F.Paste")
			(net "PV_VDDR_NODE1_VID0")
		)
		(pad "9" smd rect
			(at 2.27965 2.655062)
			(size 0.1778 0.9144)
			(layers "F.Cu" "F.Mask" "F.Paste")
			(net "PV_VDDR_NODE1_VID1")
		)
		(pad "10" smd rect
			(at 2.6797 2.655062)
			(size 0.1778 0.9144)
			(layers "F.Cu" "F.Mask" "F.Paste")
			(net "PV_VDDR_NODE1_EN")
		)
		(pad "11" smd rect
			(at 3.442462 1.8923 270)
			(size 0.1778 0.9144)
			(layers "F.Cu" "F.Mask" "F.Paste")
			(net "SW_PV_VDDR_NODE1_BT")
		)
		(pad "12" smd rect
			(at 3.442462 1.49225 270)
			(size 0.1778 0.9144)
			(layers "F.Cu" "F.Mask" "F.Paste")
			(net "SW_PV_VDDR_NODE1_PH")
		)
		(pad "13" smd rect
			(at 3.442462 1.0922 270)
			(size 0.1778 0.9144)
			(layers "F.Cu" "F.Mask" "F.Paste")
			(net "SW_PV_VDDR_NODE1_DRVH")
		)
		(pad "14" smd rect
			(at 3.442462 0.69215 270)
			(size 0.1778 0.9144)
			(layers "F.Cu" "F.Mask" "F.Paste")
			(net "SW_PV_VDDR_NODE1_DRVL")
		)
		(pad "15" smd rect
			(at 3.442462 0.2921 270)
			(size 0.1778 0.9144)
			(layers "F.Cu" "F.Mask" "F.Paste")
			(net "P5V_STB_NODE1")
		)
		(pad "16" smd rect
			(at 2.6797 -0.470662)
			(size 0.1778 0.9144)
			(layers "F.Cu" "F.Mask" "F.Paste")
			(net "PV_VDDR_NODE1_MODE")
		)
		(pad "17" smd rect
			(at 2.27965 -0.470662)
			(size 0.1778 0.9144)
			(layers "F.Cu" "F.Mask" "F.Paste")
			(net "GND")
		)
		(pad "18" smd rect
			(at 1.8796 -0.470662)
			(size 0.1778 0.9144)
			(layers "F.Cu" "F.Mask" "F.Paste")
			(net "PV_VDDR_NODE1_TRIP")
		)
		(pad "19" smd rect
			(at 1.47955 -0.470662)
			(size 0.1778 0.9144)
			(layers "F.Cu" "F.Mask" "F.Paste")
			(net "PV_VDDR_NODE1_SLEW")
		)
		(pad "20" smd rect
			(at 1.0795 -0.470662)
			(size 0.1778 0.9144)
			(layers "F.Cu" "F.Mask" "F.Paste")
			(net "VSENSE_PV_VDDR_NODE1_P")
		)
		(pad "TH" smd rect
			(at 1.8796 1.0922 90)
			(size 1.8034 1.8034)
			(layers "F.Cu" "F.Mask" "F.Paste")
			(net "GND")
		)
		(zone
			(layer "F.Cu")
			(hatch none 0.5)
			(connect_pads
				(clearance 0)
			)
			(min_thickness 0.25)
			(keepout
				(tracks allowed)
				(vias not_allowed)
				(pads allowed)
				(copperpour not_allowed)
				(footprints allowed)
			)
			(placement
				(enabled no)
				(sheetname "")
			)
			(fill
				(thermal_gap 0.5)
				(thermal_bridge_width 0.5)
				(island_removal_mode 0)
			)
			(polygon
				(pts
					(xy 37.039804 -9.272778) (xy 37.116004 -9.272778) (xy 37.116004 -11.330178) (xy 37.039804 -11.330178)
				)
			)
		)
		(zone
			(layer "F.Cu")
			(hatch none 0.5)
			(connect_pads
				(clearance 0)
			)
			(min_thickness 0.25)
			(keepout
				(tracks not_allowed)
				(vias allowed)
				(pads allowed)
				(copperpour not_allowed)
				(footprints allowed)
			)
			(placement
				(enabled no)
				(sheetname "")
			)
			(fill
				(thermal_gap 0.5)
				(thermal_bridge_width 0.5)
				(island_removal_mode 0)
			)
			(polygon
				(pts
					(xy 37.039804 -9.272778) (xy 37.116004 -9.272778) (xy 37.116004 -11.330178) (xy 37.039804 -11.330178)
				)
			)
		)
		(zone
			(layer "F.Cu")
			(hatch none 0.5)
			(connect_pads
				(clearance 0)
			)
			(min_thickness 0.25)
			(keepout
				(tracks not_allowed)
				(vias allowed)
				(pads allowed)
				(copperpour not_allowed)
				(footprints allowed)
			)
			(placement
				(enabled no)
				(sheetname "")
			)
			(fill
				(thermal_gap 0.5)
				(thermal_bridge_width 0.5)
				(island_removal_mode 0)
			)
			(polygon
				(pts
					(xy 37.116004 -11.253978) (xy 39.122604 -11.253978) (xy 39.122604 -11.330178) (xy 37.116004 -11.330178)
				)
			)
		)
		(zone
			(layer "F.Cu")
			(hatch none 0.5)
			(connect_pads
				(clearance 0)
			)
			(min_thickness 0.25)
			(keepout
				(tracks allowed)
				(vias not_allowed)
				(pads allowed)
				(copperpour not_allowed)
				(footprints allowed)
			)
			(placement
				(enabled no)
				(sheetname "")
			)
			(fill
				(thermal_gap 0.5)
				(thermal_bridge_width 0.5)
				(island_removal_mode 0)
			)
			(polygon
				(pts
					(xy 37.116004 -11.253978) (xy 39.122604 -11.253978) (xy 39.122604 -11.330178) (xy 37.116004 -11.330178)
				)
			)
		)
		(zone
			(layer "F.Cu")
			(hatch none 0.5)
			(connect_pads
				(clearance 0)
			)
			(min_thickness 0.25)
			(keepout
				(tracks not_allowed)
				(vias allowed)
				(pads allowed)
				(copperpour not_allowed)
				(footprints allowed)
			)
			(placement
				(enabled no)
				(sheetname "")
			)
			(fill
				(thermal_gap 0.5)
				(thermal_bridge_width 0.5)
				(island_removal_mode 0)
			)
			(polygon
				(pts
					(xy 37.116004 -9.272778) (xy 39.046404 -9.272778) (xy 39.046404 -9.348978) (xy 37.116004 -9.348978)
				)
			)
		)
		(zone
			(layer "F.Cu")
			(hatch none 0.5)
			(connect_pads
				(clearance 0)
			)
			(min_thickness 0.25)
			(keepout
				(tracks allowed)
				(vias not_allowed)
				(pads allowed)
				(copperpour not_allowed)
				(footprints allowed)
			)
			(placement
				(enabled no)
				(sheetname "")
			)
			(fill
				(thermal_gap 0.5)
				(thermal_bridge_width 0.5)
				(island_removal_mode 0)
			)
			(polygon
				(pts
					(xy 39.046404 -11.253978) (xy 39.122604 -11.253978) (xy 39.122604 -9.272778) (xy 39.046404 -9.272778)
				)
			)
		)
		(zone
			(layer "F.Cu")
			(hatch none 0.5)
			(connect_pads
				(clearance 0)
			)
			(min_thickness 0.25)
			(keepout
				(tracks allowed)
				(vias not_allowed)
				(pads allowed)
				(copperpour not_allowed)
				(footprints allowed)
			)
			(placement
				(enabled no)
				(sheetname "")
			)
			(fill
				(thermal_gap 0.5)
				(thermal_bridge_width 0.5)
				(island_removal_mode 0)
			)
			(polygon
				(pts
					(xy 39.046404 -9.348978) (xy 37.116004 -9.348978) (xy 37.116004 -9.272778) (xy 39.046404 -9.272778)
				)
			)
		)
		(zone
			(layer "F.Cu")
			(hatch none 0.5)
			(connect_pads
				(clearance 0)
			)
			(min_thickness 0.25)
			(keepout
				(tracks not_allowed)
				(vias allowed)
				(pads allowed)
				(copperpour not_allowed)
				(footprints allowed)
			)
			(placement
				(enabled no)
				(sheetname "")
			)
			(fill
				(thermal_gap 0.5)
				(thermal_bridge_width 0.5)
				(island_removal_mode 0)
			)
			(polygon
				(pts
					(xy 39.046404 -9.272778) (xy 39.122604 -9.272778) (xy 39.122604 -11.253978) (xy 39.046404 -11.253978)
				)
			)
		)
	)
	(footprint ""
		(layer "F.Cu")
		(at 163.687252 -90.14079 180)
		(property "Reference" "C367"
			(at 0.675386 -2.384044 0)
			(unlocked yes)
			(layer "F.SilkS")
			(effects
				(font
					(size 0.7874 0.5842)
					(thickness 0.1524)
				)
				(justify left)
			)
		)
		(property "Value" ""
			(at 0 0 180)
			(layer "F.Fab")
			(effects
				(font
					(size 1.27 1.27)
				)
			)
		)
		(duplicate_pad_numbers_are_jumpers no)
		(fp_line
			(start 0.7874 0.4064)
			(end -0.7874 0.4064)
			(stroke
				(width 0.1524)
				(type default)
			)
			(layer "F.SilkS")
		)
		(fp_line
			(start 0.7874 -0.4064)
			(end 0.7874 0.4064)
			(stroke
				(width 0.1524)
				(type default)
			)
			(layer "F.SilkS")
		)
		(fp_line
			(start 0 0.381)
			(end 0 -0.381)
			(stroke
				(width 0.1524)
				(type default)
			)
			(layer "F.SilkS")
		)
		(fp_line
			(start -0.7874 0.4064)
			(end -0.7874 -0.4064)
			(stroke
				(width 0.1524)
				(type default)
			)
			(layer "F.SilkS")
		)
		(fp_line
			(start -0.7874 -0.4064)
			(end 0.7874 -0.4064)
			(stroke
				(width 0.1524)
				(type default)
			)
			(layer "F.SilkS")
		)
		(fp_poly
			(pts
				(xy -0.5334 0.254) (xy -0.635 0.254) (xy -0.635 0.2286) (xy -0.635 -0.254) (xy -0.5334 -0.254) (xy -0.5334 -0.2794)
				(xy 0.5334 -0.2794) (xy 0.5334 -0.254) (xy 0.635 -0.254) (xy 0.635 0.254) (xy 0.5334 0.254) (xy 0.5334 0.2794)
				(xy -0.508 0.2794) (xy -0.5334 0.2794)
			)
			(stroke
				(width 0)
				(type default)
			)
			(fill no)
			(layer "F.CrtYd")
		)
		(pad "1" smd rect
			(at 0.40005 0 180)
			(size 0.4572 0.508)
			(layers "F.Cu" "F.Mask" "F.Paste")
			(net "P3V3_NODE1")
		)
		(pad "2" smd rect
			(at -0.40005 0 180)
			(size 0.4572 0.508)
			(layers "F.Cu" "F.Mask" "F.Paste")
			(net "GND")
		)
	)
	(footprint ""
		(layer "F.Cu")
		(at 141.708886 -51.476656 90)
		(property "Reference" "R1017"
			(at 16.324326 30.435042 90)
			(unlocked yes)
			(layer "F.SilkS")
			(effects
				(font
					(size 0.7874 0.5842)
					(thickness 0.1524)
				)
				(justify left)
			)
		)
		(property "Value" ""
			(at 0 0 90)
			(layer "F.Fab")
			(effects
				(font
					(size 1.27 1.27)
				)
			)
		)
		(duplicate_pad_numbers_are_jumpers no)
		(fp_line
			(start 0.7874 -0.4064)
			(end 0.7874 0.4064)
			(stroke
				(width 0.1524)
				(type default)
			)
			(layer "F.SilkS")
		)
		(fp_line
			(start -0.7874 -0.4064)
			(end 0.7874 -0.4064)
			(stroke
				(width 0.1524)
				(type default)
			)
			(layer "F.SilkS")
		)
		(fp_line
			(start 0.7874 0.4064)
			(end -0.7874 0.4064)
			(stroke
				(width 0.1524)
				(type default)
			)
			(layer "F.SilkS")
		)
		(fp_line
			(start -0.7874 0.4064)
			(end -0.7874 -0.4064)
			(stroke
				(width 0.1524)
				(type default)
			)
			(layer "F.SilkS")
		)
		(fp_poly
			(pts
				(xy -0.508 0.2794) (xy -0.508 0.2286) (xy -0.635 0.2286) (xy -0.635 -0.254) (xy -0.5334 -0.254)
				(xy -0.5334 -0.2794) (xy 0.5334 -0.2794) (xy 0.5334 -0.254) (xy 0.635 -0.254) (xy 0.635 0.254) (xy 0.5334 0.254)
				(xy 0.5334 0.2794)
			)
			(stroke
				(width 0)
				(type default)
			)
			(fill no)
			(layer "F.CrtYd")
		)
		(pad "1" smd rect
			(at 0.40005 0 90)
			(size 0.4572 0.508)
			(layers "F.Cu" "F.Mask" "F.Paste")
			(net "P5V_NODE1")
		)
		(pad "2" smd rect
			(at -0.40005 0 90)
			(size 0.4572 0.508)
			(layers "F.Cu" "F.Mask" "F.Paste")
			(net "UART_RTS_P2_N")
		)
	)
	(footprint ""
		(layer "F.Cu")
		(at 187.55614 -123.860306)
		(property "Reference" "R1033"
			(at 5.48386 18.984976 0)
			(unlocked yes)
			(layer "F.SilkS")
			(effects
				(font
					(size 0.7874 0.5842)
					(thickness 0.1524)
				)
				(justify left)
			)
		)
		(property "Value" ""
			(at 0 0 0)
			(layer "F.Fab")
			(effects
				(font
					(size 1.27 1.27)
				)
			)
		)
		(duplicate_pad_numbers_are_jumpers no)
		(fp_line
			(start -0.7874 -0.4064)
			(end 0.7874 -0.4064)
			(stroke
				(width 0.1524)
				(type default)
			)
			(layer "F.SilkS")
		)
		(fp_line
			(start -0.7874 0.4064)
			(end -0.7874 -0.4064)
			(stroke
				(width 0.1524)
				(type default)
			)
			(layer "F.SilkS")
		)
		(fp_line
			(start 0.7874 -0.4064)
			(end 0.7874 0.4064)
			(stroke
				(width 0.1524)
				(type default)
			)
			(layer "F.SilkS")
		)
		(fp_line
			(start 0.7874 0.4064)
			(end -0.7874 0.4064)
			(stroke
				(width 0.1524)
				(type default)
			)
			(layer "F.SilkS")
		)
		(fp_poly
			(pts
				(xy -0.508 0.2794) (xy -0.508 0.2286) (xy -0.635 0.2286) (xy -0.635 -0.254) (xy -0.5334 -0.254)
				(xy -0.5334 -0.2794) (xy 0.5334 -0.2794) (xy 0.5334 -0.254) (xy 0.635 -0.254) (xy 0.635 0.254) (xy 0.5334 0.254)
				(xy 0.5334 0.2794)
			)
			(stroke
				(width 0)
				(type default)
			)
			(fill no)
			(layer "F.CrtYd")
		)
		(pad "1" smd rect
			(at 0.40005 0)
			(size 0.4572 0.508)
			(layers "F.Cu" "F.Mask" "F.Paste")
			(net "GND")
		)
		(pad "2" smd rect
			(at -0.40005 0)
			(size 0.4572 0.508)
			(layers "F.Cu" "F.Mask" "F.Paste")
			(net "JTAG_CPLD1_TCK")
		)
	)
)
